FILE_TYPE=LIBRARY_PARTS;
TIME=' Created/Modified on Fri Aug 20 09:19:25 2010' ;
primitive 'MMBT3904';
  pin
    '1':
      PIN_NUMBER='(B)';
      INPUT_LOAD='(-0.01,0.01)';
    '2':
      PIN_NUMBER='(E)';
      INPUT_LOAD='(-0.01,0.01)';
      OUTPUT_LOAD='(1.0,-1.0)';
      BIDIRECTIONAL='TRUE';
    '3':
      PIN_NUMBER='(C)';
      INPUT_LOAD='(-0.01,0.01)';
      OUTPUT_LOAD='(1.0,-1.0)';
      BIDIRECTIONAL='TRUE';
  end_pin;
  body
    CLASS='DISCRETE';
    PART_NAME='MMBT3904';
    PHYS_DES_PREFIX='Q';
  end_body;
end_primitive;
END.
